(kicad_pcb
	(version 20260206)
	(generator "pcbnew")
	(generator_version "10.0")
	(general
		(thickness 1.6)
		(legacy_teardrops no)
	)
	(paper "A4")
	(title_block
		(title "04192023_DAF0TMB3IC0_F0TG_MB_C_brd_V02_OCP.brd")
		(comment 1 "Grand Teton / footprints 5524-5530 of 8354")
	)
	(layers
		(0 "F.Cu" signal "TOP")
		(4 "In1.Cu" signal "GND")
		(6 "In2.Cu" signal "IN1")
		(8 "In3.Cu" signal "GND1")
		(10 "In4.Cu" signal "IN2")
		(12 "In5.Cu" signal "GND2")
		(14 "In6.Cu" signal "IN3")
		(16 "In7.Cu" signal "GND3")
		(18 "In8.Cu" signal "VCC")
		(20 "In9.Cu" signal "VCC1")
		(22 "In10.Cu" signal "GND4")
		(24 "In11.Cu" signal "IN4")
		(26 "In12.Cu" signal "GND5")
		(28 "In13.Cu" signal "IN5")
		(30 "In14.Cu" signal "GND6")
		(32 "In15.Cu" signal "IN6")
		(34 "In16.Cu" signal "GND7")
		(2 "B.Cu" signal "BOTTOM")
		(9 "F.Adhes" user "F.Adhesive")
		(11 "B.Adhes" user "B.Adhesive")
		(13 "F.Paste" user "Package Geometry/Pastemask Top")
		(15 "B.Paste" user "Package Geometry/Pastemask Bottom")
		(5 "F.SilkS" user "Ref Des/Silkscreen Top")
		(7 "B.SilkS" user "Ref Des/Silkscreen Bottom")
		(1 "F.Mask" user "Board Geometry/Soldermask Top")
		(3 "B.Mask" user "Board Geometry/Soldermask Bottom")
		(17 "Dwgs.User" user "User.Drawings")
		(19 "Cmts.User" user "User.Comments")
		(21 "Eco1.User" user "User.Eco1")
		(23 "Eco2.User" user "User.Eco2")
		(25 "Edge.Cuts" user "Board Geometry/Outline")
		(27 "Margin" user)
		(31 "F.CrtYd" user "Package Geometry/Place Bound Top")
		(29 "B.CrtYd" user "Package Geometry/Place Bound Bottom")
		(35 "F.Fab" user "Ref Des/Assembly Top")
		(33 "B.Fab" user "Ref Des/Assembly Bottom")
	)
	(footprint ""
		(layer "B.Cu")
		(at 28.395676 -339.864954 -90)
		(property "Reference" "PC455"
			(at 9.410954 -0.914654 270)
			(unlocked yes)
			(layer "B.SilkS")
			(effects
				(font
					(size 0.7874 0.5842)
					(thickness 0.1524)
				)
				(justify left mirror)
			)
		)
		(property "Value" ""
			(at 0 0 90)
			(layer "B.Fab")
			(effects
				(font
					(size 1.27 1.27)
				)
				(justify mirror)
			)
		)
		(duplicate_pad_numbers_are_jumpers no)
		(fp_line
			(start -4.533392 2.249932)
			(end 4.533392 2.249932)
			(stroke
				(width 0.1524)
				(type default)
			)
			(layer "B.SilkS")
		)
		(fp_line
			(start 4.533392 2.249932)
			(end 4.533392 -2.249932)
			(stroke
				(width 0.1524)
				(type default)
			)
			(layer "B.SilkS")
		)
		(fp_line
			(start -4.533392 -2.249932)
			(end -4.533392 2.249932)
			(stroke
				(width 0.1524)
				(type default)
			)
			(layer "B.SilkS")
		)
		(fp_line
			(start 4.533392 -2.249932)
			(end -4.533392 -2.249932)
			(stroke
				(width 0.1524)
				(type default)
			)
			(layer "B.SilkS")
		)
		(fp_rect
			(start 5.39242 2.326132)
			(end 4.533392 -2.326132)
			(stroke
				(width 0)
				(type default)
			)
			(fill yes)
			(layer "B.SilkS")
		)
		(fp_line
			(start -3.750056 2.249932)
			(end 3.750056 2.249932)
			(stroke
				(width 0.1)
				(type default)
			)
			(layer "B.Fab")
		)
		(fp_line
			(start 3.750056 2.249932)
			(end 3.750056 -2.249932)
			(stroke
				(width 0.1)
				(type default)
			)
			(layer "B.Fab")
		)
		(fp_line
			(start -3.750056 -2.249932)
			(end -3.750056 2.249932)
			(stroke
				(width 0.1)
				(type default)
			)
			(layer "B.Fab")
		)
		(fp_line
			(start 3.750056 -2.249932)
			(end -3.750056 -2.249932)
			(stroke
				(width 0.1)
				(type default)
			)
			(layer "B.Fab")
		)
		(fp_text user "-"
			(at -4.602734 2.14122 270)
			(unlocked yes)
			(layer "B.SilkS")
			(effects
				(font
					(size 1.905 1.4224)
					(thickness 0.1524)
				)
				(justify left mirror)
			)
		)
		(fp_text user "+"
			(at 6.322314 0.786384 180)
			(unlocked yes)
			(layer "B.SilkS")
			(effects
				(font
					(size 1.905 1.4224)
					(thickness 0.1524)
				)
				(justify left mirror)
			)
		)
		(fp_text user "+"
			(at 6.322314 0.786384 180)
			(unlocked yes)
			(layer "B.Fab")
			(effects
				(font
					(size 1.905 1.4224)
					(thickness 0.1524)
				)
				(justify left mirror)
			)
		)
		(fp_text user "-"
			(at -4.8514 -0.14605 270)
			(unlocked yes)
			(layer "B.Fab")
			(effects
				(font
					(size 1.905 1.4224)
					(thickness 0.1524)
				)
				(justify left mirror)
			)
		)
		(pad "1" smd rect
			(at 3.199892 0 90)
			(size 2.413 2.8194)
			(layers "B.Cu" "B.Mask" "B.Paste")
			(net "PVDDIO_P1")
		)
		(pad "2" smd rect
			(at -3.199892 0 90)
			(size 2.413 2.8194)
			(layers "B.Cu" "B.Mask" "B.Paste")
			(net "GND")
		)
	)
	(footprint ""
		(layer "B.Cu")
		(at 361.645454 -250.25731)
		(property "Reference" "C2196"
			(at 0 0 0)
			(layer "B.SilkS")
			(hide yes)
			(effects
				(font
					(size 1.27 1.27)
				)
				(justify mirror)
			)
		)
		(property "Value" ""
			(at 0 0 0)
			(layer "B.Fab")
			(effects
				(font
					(size 1.27 1.27)
				)
				(justify mirror)
			)
		)
		(duplicate_pad_numbers_are_jumpers no)
		(fp_line
			(start -0.7874 -0.4064)
			(end -0.7874 0.4064)
			(stroke
				(width 0.1524)
				(type default)
			)
			(layer "B.SilkS")
		)
		(fp_line
			(start -0.7874 0.4064)
			(end 0.7874 0.4064)
			(stroke
				(width 0.1524)
				(type default)
			)
			(layer "B.SilkS")
		)
		(fp_line
			(start 0.7874 -0.4064)
			(end -0.7874 -0.4064)
			(stroke
				(width 0.1524)
				(type default)
			)
			(layer "B.SilkS")
		)
		(fp_line
			(start 0.7874 0.4064)
			(end 0.7874 -0.4064)
			(stroke
				(width 0.1524)
				(type default)
			)
			(layer "B.SilkS")
		)
		(fp_line
			(start -0.67945 -0.3048)
			(end -0.67945 0.3048)
			(stroke
				(width 0.1)
				(type default)
			)
			(layer "B.Fab")
		)
		(fp_line
			(start -0.67945 0.3048)
			(end -0.120396 0.3048)
			(stroke
				(width 0.1)
				(type default)
			)
			(layer "B.Fab")
		)
		(fp_line
			(start -0.12065 -0.3048)
			(end -0.67945 -0.3048)
			(stroke
				(width 0.1)
				(type default)
			)
			(layer "B.Fab")
		)
		(fp_line
			(start -0.12065 -0.2794)
			(end -0.12065 -0.3048)
			(stroke
				(width 0.1)
				(type default)
			)
			(layer "B.Fab")
		)
		(fp_line
			(start -0.120396 0.2794)
			(end 0.12065 0.2794)
			(stroke
				(width 0.1)
				(type default)
			)
			(layer "B.Fab")
		)
		(fp_line
			(start -0.120396 0.3048)
			(end -0.120396 0.2794)
			(stroke
				(width 0.1)
				(type default)
			)
			(layer "B.Fab")
		)
		(fp_line
			(start 0.12065 -0.305054)
			(end 0.12065 -0.2794)
			(stroke
				(width 0.1)
				(type default)
			)
			(layer "B.Fab")
		)
		(fp_line
			(start 0.12065 -0.2794)
			(end -0.12065 -0.2794)
			(stroke
				(width 0.1)
				(type default)
			)
			(layer "B.Fab")
		)
		(fp_line
			(start 0.12065 0.2794)
			(end 0.12065 0.3048)
			(stroke
				(width 0.1)
				(type default)
			)
			(layer "B.Fab")
		)
		(fp_line
			(start 0.12065 0.3048)
			(end 0.67945 0.3048)
			(stroke
				(width 0.1)
				(type default)
			)
			(layer "B.Fab")
		)
		(fp_line
			(start 0.67945 -0.305054)
			(end 0.12065 -0.305054)
			(stroke
				(width 0.1)
				(type default)
			)
			(layer "B.Fab")
		)
		(fp_line
			(start 0.67945 0.3048)
			(end 0.67945 -0.305054)
			(stroke
				(width 0.1)
				(type default)
			)
			(layer "B.Fab")
		)
		(pad "1" smd circle
			(at 0.40005 0 180)
			(size 0 0)
			(layers "B.Cu" "B.Mask" "B.Paste")
			(net "PVDDCR_CPU0_P0")
		)
		(pad "2" smd circle
			(at -0.40005 0 180)
			(size 0 0)
			(layers "B.Cu" "B.Mask" "B.Paste")
			(net "GND")
		)
	)
	(footprint ""
		(layer "B.Cu")
		(at 355.295454 -269.30731 180)
		(property "Reference" "C2201"
			(at 0 0 0)
			(layer "B.SilkS")
			(hide yes)
			(effects
				(font
					(size 1.27 1.27)
				)
				(justify mirror)
			)
		)
		(property "Value" ""
			(at 0 0 0)
			(layer "B.Fab")
			(effects
				(font
					(size 1.27 1.27)
				)
				(justify mirror)
			)
		)
		(duplicate_pad_numbers_are_jumpers no)
		(fp_line
			(start 0.7874 0.4064)
			(end 0.7874 -0.4064)
			(stroke
				(width 0.1524)
				(type default)
			)
			(layer "B.SilkS")
		)
		(fp_line
			(start 0.7874 -0.4064)
			(end -0.7874 -0.4064)
			(stroke
				(width 0.1524)
				(type default)
			)
			(layer "B.SilkS")
		)
		(fp_line
			(start -0.7874 0.4064)
			(end 0.7874 0.4064)
			(stroke
				(width 0.1524)
				(type default)
			)
			(layer "B.SilkS")
		)
		(fp_line
			(start -0.7874 -0.4064)
			(end -0.7874 0.4064)
			(stroke
				(width 0.1524)
				(type default)
			)
			(layer "B.SilkS")
		)
		(fp_line
			(start 0.67945 0.3048)
			(end 0.67945 -0.305054)
			(stroke
				(width 0.1)
				(type default)
			)
			(layer "B.Fab")
		)
		(fp_line
			(start 0.67945 -0.305054)
			(end 0.12065 -0.305054)
			(stroke
				(width 0.1)
				(type default)
			)
			(layer "B.Fab")
		)
		(fp_line
			(start 0.12065 0.3048)
			(end 0.67945 0.3048)
			(stroke
				(width 0.1)
				(type default)
			)
			(layer "B.Fab")
		)
		(fp_line
			(start 0.12065 0.2794)
			(end 0.12065 0.3048)
			(stroke
				(width 0.1)
				(type default)
			)
			(layer "B.Fab")
		)
		(fp_line
			(start 0.12065 -0.2794)
			(end -0.12065 -0.2794)
			(stroke
				(width 0.1)
				(type default)
			)
			(layer "B.Fab")
		)
		(fp_line
			(start 0.12065 -0.305054)
			(end 0.12065 -0.2794)
			(stroke
				(width 0.1)
				(type default)
			)
			(layer "B.Fab")
		)
		(fp_line
			(start -0.120396 0.3048)
			(end -0.120396 0.2794)
			(stroke
				(width 0.1)
				(type default)
			)
			(layer "B.Fab")
		)
		(fp_line
			(start -0.120396 0.2794)
			(end 0.12065 0.2794)
			(stroke
				(width 0.1)
				(type default)
			)
			(layer "B.Fab")
		)
		(fp_line
			(start -0.12065 -0.2794)
			(end -0.12065 -0.3048)
			(stroke
				(width 0.1)
				(type default)
			)
			(layer "B.Fab")
		)
		(fp_line
			(start -0.12065 -0.3048)
			(end -0.67945 -0.3048)
			(stroke
				(width 0.1)
				(type default)
			)
			(layer "B.Fab")
		)
		(fp_line
			(start -0.67945 0.3048)
			(end -0.120396 0.3048)
			(stroke
				(width 0.1)
				(type default)
			)
			(layer "B.Fab")
		)
		(fp_line
			(start -0.67945 -0.3048)
			(end -0.67945 0.3048)
			(stroke
				(width 0.1)
				(type default)
			)
			(layer "B.Fab")
		)
		(pad "1" smd circle
			(at 0.40005 0)
			(size 0 0)
			(layers "B.Cu" "B.Mask" "B.Paste")
			(net "PVDDCR_CPU1_P0")
		)
		(pad "2" smd circle
			(at -0.40005 0)
			(size 0 0)
			(layers "B.Cu" "B.Mask" "B.Paste")
			(net "GND")
		)
	)
	(footprint ""
		(layer "B.Cu")
		(at 86.059264 -408.517344 90)
		(property "Reference" "C6686"
			(at 0 0 90)
			(layer "B.SilkS")
			(hide yes)
			(effects
				(font
					(size 1.27 1.27)
				)
				(justify mirror)
			)
		)
		(property "Value" ""
			(at 0 0 90)
			(layer "B.Fab")
			(effects
				(font
					(size 1.27 1.27)
				)
				(justify mirror)
			)
		)
		(duplicate_pad_numbers_are_jumpers no)
		(fp_line
			(start 0.299974 -0.150114)
			(end -0.299974 -0.150114)
			(stroke
				(width 0.1)
				(type default)
			)
			(layer "B.Fab")
		)
		(fp_line
			(start -0.299974 -0.150114)
			(end -0.299974 0.150114)
			(stroke
				(width 0.1)
				(type default)
			)
			(layer "B.Fab")
		)
		(fp_line
			(start 0.299974 0.150114)
			(end 0.299974 -0.150114)
			(stroke
				(width 0.1)
				(type default)
			)
			(layer "B.Fab")
		)
		(fp_line
			(start -0.299974 0.150114)
			(end 0.299974 0.150114)
			(stroke
				(width 0.1)
				(type default)
			)
			(layer "B.Fab")
		)
		(pad "1" smd rect
			(at 0.2667 0 270)
			(size 0.3048 0.381)
			(layers "B.Cu" "B.Mask" "B.Paste")
			(net "P5E_CPU1_P1_TX_BUF_C_DN<12>")
		)
		(pad "2" smd rect
			(at -0.2667 0 270)
			(size 0.3048 0.381)
			(layers "B.Cu" "B.Mask" "B.Paste")
			(net "P5E_CPU1_P1_TX_BUF_DN<12>")
		)
	)
	(footprint ""
		(layer "B.Cu")
		(at 343.245948 -396.393162 -90)
		(property "Reference" "C597"
			(at 0 0 90)
			(layer "B.SilkS")
			(hide yes)
			(effects
				(font
					(size 1.27 1.27)
				)
				(justify mirror)
			)
		)
		(property "Value" ""
			(at 0 0 90)
			(layer "B.Fab")
			(effects
				(font
					(size 1.27 1.27)
				)
				(justify mirror)
			)
		)
		(duplicate_pad_numbers_are_jumpers no)
		(fp_line
			(start -0.299974 0.150114)
			(end 0.299974 0.150114)
			(stroke
				(width 0.1)
				(type default)
			)
			(layer "B.Fab")
		)
		(fp_line
			(start 0.299974 0.150114)
			(end 0.299974 -0.150114)
			(stroke
				(width 0.1)
				(type default)
			)
			(layer "B.Fab")
		)
		(fp_line
			(start -0.299974 -0.150114)
			(end -0.299974 0.150114)
			(stroke
				(width 0.1)
				(type default)
			)
			(layer "B.Fab")
		)
		(fp_line
			(start 0.299974 -0.150114)
			(end -0.299974 -0.150114)
			(stroke
				(width 0.1)
				(type default)
			)
			(layer "B.Fab")
		)
		(pad "1" smd rect
			(at 0.2667 0 90)
			(size 0.3048 0.381)
			(layers "B.Cu" "B.Mask" "B.Paste")
			(net "P1V8_CPU0_RT1_1A")
		)
		(pad "2" smd rect
			(at -0.2667 0 90)
			(size 0.3048 0.381)
			(layers "B.Cu" "B.Mask" "B.Paste")
			(net "GND")
		)
	)
	(footprint ""
		(layer "B.Cu")
		(at 427.558454 -191.32931 180)
		(property "Reference" "R299"
			(at 0 0 0)
			(layer "B.SilkS")
			(hide yes)
			(effects
				(font
					(size 1.27 1.27)
				)
				(justify mirror)
			)
		)
		(property "Value" ""
			(at 0 0 0)
			(layer "B.Fab")
			(effects
				(font
					(size 1.27 1.27)
				)
				(justify mirror)
			)
		)
		(duplicate_pad_numbers_are_jumpers no)
		(fp_line
			(start 0.7874 0.4064)
			(end 0.7874 -0.4064)
			(stroke
				(width 0.1524)
				(type default)
			)
			(layer "B.SilkS")
		)
		(fp_line
			(start 0.7874 -0.4064)
			(end -0.7874 -0.4064)
			(stroke
				(width 0.1524)
				(type default)
			)
			(layer "B.SilkS")
		)
		(fp_line
			(start -0.7874 0.4064)
			(end 0.7874 0.4064)
			(stroke
				(width 0.1524)
				(type default)
			)
			(layer "B.SilkS")
		)
		(fp_line
			(start -0.7874 -0.4064)
			(end -0.7874 0.4064)
			(stroke
				(width 0.1524)
				(type default)
			)
			(layer "B.SilkS")
		)
		(fp_line
			(start 0.67945 0.3048)
			(end 0.67945 -0.305054)
			(stroke
				(width 0.1)
				(type default)
			)
			(layer "B.Fab")
		)
		(fp_line
			(start 0.67945 -0.305054)
			(end 0.12065 -0.305054)
			(stroke
				(width 0.1)
				(type default)
			)
			(layer "B.Fab")
		)
		(fp_line
			(start 0.12065 0.3048)
			(end 0.67945 0.3048)
			(stroke
				(width 0.1)
				(type default)
			)
			(layer "B.Fab")
		)
		(fp_line
			(start 0.12065 0.2794)
			(end 0.12065 0.3048)
			(stroke
				(width 0.1)
				(type default)
			)
			(layer "B.Fab")
		)
		(fp_line
			(start 0.12065 -0.2794)
			(end -0.12065 -0.2794)
			(stroke
				(width 0.1)
				(type default)
			)
			(layer "B.Fab")
		)
		(fp_line
			(start 0.12065 -0.305054)
			(end 0.12065 -0.2794)
			(stroke
				(width 0.1)
				(type default)
			)
			(layer "B.Fab")
		)
		(fp_line
			(start -0.120396 0.3048)
			(end -0.120396 0.2794)
			(stroke
				(width 0.1)
				(type default)
			)
			(layer "B.Fab")
		)
		(fp_line
			(start -0.120396 0.2794)
			(end 0.12065 0.2794)
			(stroke
				(width 0.1)
				(type default)
			)
			(layer "B.Fab")
		)
		(fp_line
			(start -0.12065 -0.2794)
			(end -0.12065 -0.3048)
			(stroke
				(width 0.1)
				(type default)
			)
			(layer "B.Fab")
		)
		(fp_line
			(start -0.12065 -0.3048)
			(end -0.67945 -0.3048)
			(stroke
				(width 0.1)
				(type default)
			)
			(layer "B.Fab")
		)
		(fp_line
			(start -0.67945 0.3048)
			(end -0.120396 0.3048)
			(stroke
				(width 0.1)
				(type default)
			)
			(layer "B.Fab")
		)
		(fp_line
			(start -0.67945 -0.3048)
			(end -0.67945 0.3048)
			(stroke
				(width 0.1)
				(type default)
			)
			(layer "B.Fab")
		)
		(pad "1" smd circle
			(at 0.40005 0)
			(size 0 0)
			(layers "B.Cu" "B.Mask" "B.Paste")
			(net "PWRGD_CHI_CPU0_DIMM")
		)
		(pad "2" smd circle
			(at -0.40005 0)
			(size 0 0)
			(layers "B.Cu" "B.Mask" "B.Paste")
			(net "PWRGD_CHGL_CPU0")
		)
	)
	(footprint ""
		(layer "B.Cu")
		(at 186.22264 -133.208014 90)
		(property "Reference" "R6799"
			(at 0 0 90)
			(layer "B.SilkS")
			(hide yes)
			(effects
				(font
					(size 1.27 1.27)
				)
				(justify mirror)
			)
		)
		(property "Value" ""
			(at 0 0 90)
			(layer "B.Fab")
			(effects
				(font
					(size 1.27 1.27)
				)
				(justify mirror)
			)
		)
		(duplicate_pad_numbers_are_jumpers no)
		(fp_line
			(start 0.7874 -0.4064)
			(end -0.7874 -0.4064)
			(stroke
				(width 0.1524)
				(type default)
			)
			(layer "B.SilkS")
		)
		(fp_line
			(start -0.7874 -0.4064)
			(end -0.7874 0.4064)
			(stroke
				(width 0.1524)
				(type default)
			)
			(layer "B.SilkS")
		)
		(fp_line
			(start 0.7874 0.4064)
			(end 0.7874 -0.4064)
			(stroke
				(width 0.1524)
				(type default)
			)
			(layer "B.SilkS")
		)
		(fp_line
			(start -0.7874 0.4064)
			(end 0.7874 0.4064)
			(stroke
				(width 0.1524)
				(type default)
			)
			(layer "B.SilkS")
		)
		(fp_line
			(start 0.67945 -0.305054)
			(end 0.12065 -0.305054)
			(stroke
				(width 0.1)
				(type default)
			)
			(layer "B.Fab")
		)
		(fp_line
			(start 0.12065 -0.305054)
			(end 0.12065 -0.2794)
			(stroke
				(width 0.1)
				(type default)
			)
			(layer "B.Fab")
		)
		(fp_line
			(start -0.12065 -0.3048)
			(end -0.67945 -0.3048)
			(stroke
				(width 0.1)
				(type default)
			)
			(layer "B.Fab")
		)
		(fp_line
			(start -0.67945 -0.3048)
			(end -0.67945 0.3048)
			(stroke
				(width 0.1)
				(type default)
			)
			(layer "B.Fab")
		)
		(fp_line
			(start 0.12065 -0.2794)
			(end -0.12065 -0.2794)
			(stroke
				(width 0.1)
				(type default)
			)
			(layer "B.Fab")
		)
		(fp_line
			(start -0.12065 -0.2794)
			(end -0.12065 -0.3048)
			(stroke
				(width 0.1)
				(type default)
			)
			(layer "B.Fab")
		)
		(fp_line
			(start 0.12065 0.2794)
			(end 0.12065 0.3048)
			(stroke
				(width 0.1)
				(type default)
			)
			(layer "B.Fab")
		)
		(fp_line
			(start -0.120396 0.2794)
			(end 0.12065 0.2794)
			(stroke
				(width 0.1)
				(type default)
			)
			(layer "B.Fab")
		)
		(fp_line
			(start 0.67945 0.3048)
			(end 0.67945 -0.305054)
			(stroke
				(width 0.1)
				(type default)
			)
			(layer "B.Fab")
		)
		(fp_line
			(start 0.12065 0.3048)
			(end 0.67945 0.3048)
			(stroke
				(width 0.1)
				(type default)
			)
			(layer "B.Fab")
		)
		(fp_line
			(start -0.120396 0.3048)
			(end -0.120396 0.2794)
			(stroke
				(width 0.1)
				(type default)
			)
			(layer "B.Fab")
		)
		(fp_line
			(start -0.67945 0.3048)
			(end -0.120396 0.3048)
			(stroke
				(width 0.1)
				(type default)
			)
			(layer "B.Fab")
		)
		(pad "1" smd circle
			(at 0.40005 0 270)
			(size 0 0)
			(layers "B.Cu" "B.Mask" "B.Paste")
			(net "RST_RT_CPU1_P3_RESET_R_N")
		)
		(pad "2" smd circle
			(at -0.40005 0 270)
			(size 0 0)
			(layers "B.Cu" "B.Mask" "B.Paste")
			(net "RST_RT_CPU1_P3_RESET_R2_N")
		)
	)
)
